#ISCELL
  pure_quanta quanta_title_block_c *
  *
#CELL
  pure_quanta pt5161lrs *
  page447_i1
#ISCELL
  standard tap *
  page447_i10
#ISCELL
  standard tap *
  page447_i11
#ISCELL
  standard tap *
  page447_i12
#ISCELL
  standard tap *
  page447_i13
#ISCELL
  standard tap *
  page447_i14
#ISCELL
  standard tap *
  page447_i15
#ISCELL
  standard tap *
  page447_i16
#ISCELL
  standard tap *
  page447_i17
#ISCELL
  standard offpage *
  page447_i18
#ISCELL
  standard offpage *
  page447_i19
#ISCELL
  standard tap *
  page447_i2
#ISCELL
  standard tap *
  page447_i20
#ISCELL
  standard tap *
  page447_i21
#ISCELL
  standard tap *
  page447_i22
#ISCELL
  standard tap *
  page447_i23
#ISCELL
  standard tap *
  page447_i24
#ISCELL
  standard tap *
  page447_i25
#ISCELL
  standard tap *
  page447_i26
#ISCELL
  standard tap *
  page447_i27
#ISCELL
  standard tap *
  page447_i28
#ISCELL
  standard tap *
  page447_i29
#ISCELL
  standard tap *
  page447_i3
#ISCELL
  standard tap *
  page447_i30
#ISCELL
  standard tap *
  page447_i31
#ISCELL
  standard tap *
  page447_i32
#ISCELL
  standard tap *
  page447_i33
#ISCELL
  standard tap *
  page447_i34
#ISCELL
  standard tap *
  page447_i35
#ISCELL
  standard offpage *
  page447_i36
#ISCELL
  standard offpage *
  page447_i37
#CELL
  pure_quanta pt5161lrs *
  page447_i38
#ISCELL
  standard tap *
  page447_i4
#ISCELL
  standard tap *
  page447_i5
#ISCELL
  standard tap *
  page447_i6
#ISCELL
  standard tap *
  page447_i7
#ISCELL
  standard tap *
  page447_i8
#ISCELL
  standard tap *
  page447_i9
